FILE_TYPE = CONNECTIVITY;
{Allegro Design Entry HDL 16.6-p007 (v16-6-112F) 10/10/2012}
"PAGE_NUMBER" = 134;
0"NC";
1"GND\g";
2"P3V3_STBY\g";
3"P1V05_PCH_STBY\g";
4"FM_THERMTRIP_DLY";
5"FM_THERMTRIP_DLY_R";
6"FM_PCH_LVC1_THERMTRIP_N";
7"RST_PLTRST_BUF_N";
8"FM_PCH_BMC_THERMTRIP_N";
9"FM_PCH_BMC_THERMTRIP_EXI_STRAP_N";
%"RES"
"1","(-3950,4300)","0","mstr_discrete","I11";
;
CDS_SEC"1"
MATERIAL"CHIP"
PACK_TYPE"0402"
TOLERANCE"1%"
VALUE"1.00K"
PART_NUMBER"G21796-026"
LOCATION"R7D18"
WATTAGE"1/16W"
ROOM"PROC_SIDEBAND"
CDS_LOCATION"R7D18"
SEC"1"
CDS_LIB"mstr_discrete"
SEC_TYPE"0402";
"B"
$PN"2"5;
"A"
$PN"1"4;
%"GND"
"1","(-2875,3950)","0","mstr_symbols","I12";
;
HDL_POWER"GND"
BODY_TYPE"PLUMBING"
SIZE"1B"
CDS_LIB"mstr_symbols"
BOM_COST"SB"
VOLTAGE"0";
"A\NAC"1;
%"FET_N"
"8","(-2875,4400)","0","mstr_discrete","I14";
;
CDS_SEC"1"
$SEC"1"
CDS_LOCATION"Q7D1"
LOCATION"Q7D1"
VALUE"2N7002"
MATERIAL"FET"
PART_NUMBER"C79254-001"
CDS_LIB"mstr_discrete"
ROOM"HOT_SWAP"
PACK_TYPE"SOT23LF";
"GATE"
$PN"1"5;
"DRN"
$PN"3"6;
"SRC"
$PN"2"1;
%"FET_N"
"8","(700,4375)","0","mstr_discrete","I15";
;
CDS_SEC"1"
$SEC"1"
CDS_LOCATION"Q8D2"
PART_NUMBER"C79254-001"
MATERIAL"FET"
LOCATION"Q8D2"
VALUE"2N7002"
PACK_TYPE"SOT23LF"
ROOM"HOT_SWAP"
CDS_LIB"mstr_discrete";
"GATE"
$PN"1"7;
"DRN"
$PN"3"8;
"SRC"
$PN"2"9;
%"P3V3_STBY"
"1","(700,5200)","0","mstr_symbols","I2";
;
HDL_POWER"P3V3_STBY"
BODY_TYPE"PLUMBING"
CDS_LIB"mstr_symbols"
SIZE"1B"
VOLTAGE"3.3V";
"G\NAC"2;
%"RES"
"2","(700,4925)","0","mstr_discrete","I3";
;
CDS_SEC"1"
CDS_LOCATION"R2P17"
WATTAGE"1/16W"
MATERIAL"CHIP"
PACK_TYPE"0402"
TOLERANCE"1%"
VALUE"4.75K"
PART_NUMBER"G21796-072"
LOCATION"R2P17"
ROOM"THERMTRIP_PCH"
SEC"1"
SEC_TYPE"0402"
CDS_LIB"mstr_discrete"
BOM_COST"SB";
"A"
$PN"1"2;
"B"
$PN"2"8;
%"P1V05_PCH_STBY"
"1","(-2875,5100)","0","mstr_symbols","I8";
;
HDL_POWER"P1V05_PCH_STBY"
BODY_TYPE"PLUMBING"
CDS_LIB"mstr_symbols"
VOLTAGE"1.05V";
"G\NAC"3;
%"RES"
"2","(-2875,4875)","0","mstr_discrete","I9";
;
CDS_SEC"1"
WATTAGE"1/16W"
MATERIAL"CHIP"
PACK_TYPE"0402"
TOLERANCE"1%"
VALUE"10.0K"
LOCATION"R7C21"
PART_NUMBER"G21796-016"
ROOM"THERMTRIP_PCH"
CDS_LOCATION"R7C21"
SEC"1"
CDS_LIB"mstr_discrete"
SEC_TYPE"0402"
BOM_COST"SB";
"A"
$PN"1"3;
"B"
$PN"2"6;
END.
